#ISCELL
  pure_quanta quanta_title_block_c *
  *
#CELL
  pure_quanta pt5161lrs *
  page458_i1
#ISCELL
  standard tap *
  page458_i10
#ISCELL
  standard tap *
  page458_i11
#ISCELL
  standard tap *
  page458_i12
#ISCELL
  standard tap *
  page458_i13
#ISCELL
  standard tap *
  page458_i14
#ISCELL
  standard tap *
  page458_i15
#ISCELL
  standard tap *
  page458_i16
#ISCELL
  standard tap *
  page458_i17
#ISCELL
  standard offpage *
  page458_i18
#ISCELL
  standard offpage *
  page458_i19
#ISCELL
  standard tap *
  page458_i2
#ISCELL
  standard tap *
  page458_i20
#ISCELL
  standard tap *
  page458_i21
#ISCELL
  standard tap *
  page458_i22
#ISCELL
  standard tap *
  page458_i23
#ISCELL
  standard tap *
  page458_i24
#ISCELL
  standard tap *
  page458_i25
#ISCELL
  standard tap *
  page458_i26
#ISCELL
  standard tap *
  page458_i27
#ISCELL
  standard tap *
  page458_i28
#ISCELL
  standard tap *
  page458_i29
#ISCELL
  standard tap *
  page458_i3
#ISCELL
  standard tap *
  page458_i30
#ISCELL
  standard tap *
  page458_i31
#ISCELL
  standard tap *
  page458_i32
#ISCELL
  standard tap *
  page458_i33
#ISCELL
  standard tap *
  page458_i34
#ISCELL
  standard tap *
  page458_i35
#ISCELL
  standard offpage *
  page458_i36
#ISCELL
  standard offpage *
  page458_i37
#CELL
  pure_quanta pt5161lrs *
  page458_i38
#ISCELL
  standard tap *
  page458_i4
#ISCELL
  standard tap *
  page458_i5
#ISCELL
  standard tap *
  page458_i6
#ISCELL
  standard tap *
  page458_i7
#ISCELL
  standard tap *
  page458_i8
#ISCELL
  standard tap *
  page458_i9
